FILE_TYPE=LIBRARY_PARTS;
primitive 'CONN10_HBC1051L300D8H';
  pin
    '1':
      PIN_NUMBER='(1)';
      BIDIRECTIONAL='TRUE';
      INPUT_LOAD='(-0.01,0.01)';
      OUTPUT_LOAD='(1.0,-1.0)';
    '2':
      PIN_NUMBER='(2)';
      BIDIRECTIONAL='TRUE';
      INPUT_LOAD='(-0.01,0.01)';
      OUTPUT_LOAD='(1.0,-1.0)';
    '3':
      PIN_NUMBER='(3)';
      BIDIRECTIONAL='TRUE';
      INPUT_LOAD='(-0.01,0.01)';
      OUTPUT_LOAD='(1.0,-1.0)';
    '4':
      PIN_NUMBER='(4)';
      BIDIRECTIONAL='TRUE';
      INPUT_LOAD='(-0.01,0.01)';
      OUTPUT_LOAD='(1.0,-1.0)';
    '5':
      PIN_NUMBER='(5)';
      BIDIRECTIONAL='TRUE';
      INPUT_LOAD='(-0.01,0.01)';
      OUTPUT_LOAD='(1.0,-1.0)';
    '6':
      PIN_NUMBER='(6)';
      BIDIRECTIONAL='TRUE';
      INPUT_LOAD='(-0.01,0.01)';
      OUTPUT_LOAD='(1.0,-1.0)';
    '7':
      PIN_NUMBER='(7)';
      BIDIRECTIONAL='TRUE';
      INPUT_LOAD='(-0.01,0.01)';
      OUTPUT_LOAD='(1.0,-1.0)';
    '9':
      PIN_NUMBER='(9)';
      BIDIRECTIONAL='TRUE';
      INPUT_LOAD='(-0.01,0.01)';
      OUTPUT_LOAD='(1.0,-1.0)';
    '8':
      PIN_NUMBER='(8)';
      BIDIRECTIONAL='TRUE';
      INPUT_LOAD='(-0.01,0.01)';
      OUTPUT_LOAD='(1.0,-1.0)';
    '10':
      PIN_NUMBER='(10)';
      BIDIRECTIONAL='TRUE';
      INPUT_LOAD='(-0.01,0.01)';
      OUTPUT_LOAD='(1.0,-1.0)';
  end_pin;
  body
    PART_NAME='CONN10_HBC1051L300D8H';
    BODY_NAME='CONN10_HBC1051L300D8H';
    PHYS_DES_PREFIX='J';
    CLASS='IO';
  end_body;
end_primitive;

END.
